(kicad_pcb
	(version 20241229)
	(generator "pcbnew")
	(generator_version "9.0")
	(general
		(thickness 1.6296)
		(legacy_teardrops no)
	)
	(paper "A3")
	(title_block
		(title "Thunderbolt to 10GbE adapter")
		(date "2026-04-21")
		(rev "1.1.0")
		(company "Antmicro Ltd")
		(comment 1 "www.antmicro.com")
		(comment 9 "footprints 441-444 of 703")
	)
	(layers
		(0 "F.Cu" signal)
		(4 "In1.Cu" signal)
		(6 "In2.Cu" signal)
		(8 "In3.Cu" signal)
		(10 "In4.Cu" signal)
		(12 "In5.Cu" signal)
		(14 "In6.Cu" signal)
		(2 "B.Cu" signal)
		(9 "F.Adhes" user "F.Adhesive")
		(11 "B.Adhes" user "B.Adhesive")
		(13 "F.Paste" user)
		(15 "B.Paste" user)
		(5 "F.SilkS" user "F.Silkscreen")
		(7 "B.SilkS" user "B.Silkscreen")
		(1 "F.Mask" user)
		(3 "B.Mask" user)
		(17 "Dwgs.User" user "User.Drawings")
		(19 "Cmts.User" user "User.Comments")
		(21 "Eco1.User" user "User.Eco1")
		(23 "Eco2.User" user "User.Eco2")
		(25 "Edge.Cuts" user)
		(27 "Margin" user)
		(31 "F.CrtYd" user "F.Courtyard")
		(29 "B.CrtYd" user "B.Courtyard")
		(35 "F.Fab" user)
		(33 "B.Fab" user)
	)
	(footprint "antmicro-footprints:TP_SMD_0.75mm"
		(layer "B.Cu")
		(at 151.2 87 180)
		(property "Reference" "TP35"
			(at -17.6 -9.2 270)
			(layer "B.SilkS")
			(effects
				(font
					(size 0.7 0.7)
					(thickness 0.15)
				)
				(justify mirror)
			)
		)
		(property "Value" "TP_0.75mm_SMD"
			(at 0 -1.2 0)
			(layer "B.Fab")
			(effects
				(font
					(size 0.7 0.7)
					(thickness 0.15)
				)
				(justify left bottom mirror)
			)
		)
		(property "Description" "SMT test point"
			(at 0 0 0)
			(layer "B.Fab")
			(hide yes)
			(effects
				(font
					(size 1.27 1.27)
					(thickness 0.15)
				)
				(justify mirror)
			)
		)
		(property "MPN" ""
			(at 0 0 180)
			(unlocked yes)
			(layer "B.Fab")
			(hide yes)
			(effects
				(font
					(size 1 1)
					(thickness 0.15)
				)
				(justify mirror)
			)
		)
		(property "Manufacturer" ""
			(at 0 0 180)
			(unlocked yes)
			(layer "B.Fab")
			(hide yes)
			(effects
				(font
					(size 1 1)
					(thickness 0.15)
				)
				(justify mirror)
			)
		)
		(property "Author" "Antmicro"
			(at 0 0 180)
			(unlocked yes)
			(layer "B.Fab")
			(hide yes)
			(effects
				(font
					(size 1 1)
					(thickness 0.15)
				)
				(justify mirror)
			)
		)
		(property "License" "Apache-2.0"
			(at 0 0 180)
			(unlocked yes)
			(layer "B.Fab")
			(hide yes)
			(effects
				(font
					(size 1 1)
					(thickness 0.15)
				)
				(justify mirror)
			)
		)
		(sheetname "/X710-AT2 Misc/")
		(sheetfile "x710-at2-mics.kicad_sch")
		(attr exclude_from_pos_files exclude_from_bom)
		(fp_circle
			(center 0 0)
			(end 0.475 0)
			(stroke
				(width 0.05)
				(type default)
			)
			(fill no)
			(layer "B.CrtYd")
		)
		(fp_text user "Author: Antmicro"
			(at -0.4 -3.901 0)
			(layer "B.Fab")
			(effects
				(font
					(size 0.7 0.7)
					(thickness 0.15)
				)
				(justify left bottom mirror)
			)
		)
		(fp_text user "License: Apache-2.0"
			(at -0.4 -5.101 0)
			(layer "B.Fab")
			(effects
				(font
					(size 0.7 0.7)
					(thickness 0.15)
				)
				(justify left bottom mirror)
			)
		)
		(fp_text user "${REFERENCE}"
			(at -0.4 -2.7 0)
			(layer "B.Fab")
			(effects
				(font
					(size 0.7 0.7)
					(thickness 0.15)
				)
				(justify left bottom mirror)
			)
		)
		(pad "1" smd circle
			(at 0 0 180)
			(size 0.75 0.75)
			(layers "B.Cu" "B.Mask")
			(net 444 "Net-(U14D-SMBCLK)")
			(pinfunction "1")
			(pintype "passive")
		)
	)
	(footprint "antmicro-footprints:C_0402_1005Metric"
		(layer "B.Cu")
		(at 128.009999 118.61 180)
		(descr "Capacitor SMD 0402")
		(tags "capacitor SMD 0402")
		(property "Reference" "C99"
			(at -21.900002 7.700002 0)
			(layer "B.SilkS")
			(effects
				(font
					(size 0.7 0.7)
					(thickness 0.15)
				)
				(justify mirror)
			)
		)
		(property "Value" "C_100n_0402"
			(at -1.022927 -2.155213 0)
			(layer "B.Fab")
			(effects
				(font
					(size 0.7 0.7)
					(thickness 0.15)
				)
				(justify left bottom mirror)
			)
		)
		(property "Datasheet" "https://www.murata.com/products/productdetail?partno=GRM155R61H104KE14%23"
			(at 0 0 0)
			(layer "B.Fab")
			(hide yes)
			(effects
				(font
					(size 1.27 1.27)
					(thickness 0.15)
				)
				(justify mirror)
			)
		)
		(property "Description" "SMD Multilayer Ceramic Capacitor, 0.1 µF, 50 V, 0402 [1005 Metric], ± 10%, X5R, GRM Series"
			(at 0 0 0)
			(layer "B.Fab")
			(hide yes)
			(effects
				(font
					(size 1.27 1.27)
					(thickness 0.15)
				)
				(justify mirror)
			)
		)
		(property "MPN" "GRM155R61H104KE14D"
			(at 0 0 180)
			(unlocked yes)
			(layer "B.Fab")
			(hide yes)
			(effects
				(font
					(size 1 1)
					(thickness 0.15)
				)
				(justify mirror)
			)
		)
		(property "Manufacturer" "Murata"
			(at 0 0 180)
			(unlocked yes)
			(layer "B.Fab")
			(hide yes)
			(effects
				(font
					(size 1 1)
					(thickness 0.15)
				)
				(justify mirror)
			)
		)
		(property "License" "Apache-2.0"
			(at 0 0 180)
			(unlocked yes)
			(layer "B.Fab")
			(hide yes)
			(effects
				(font
					(size 1 1)
					(thickness 0.15)
				)
				(justify mirror)
			)
		)
		(property "Val" "100n"
			(at 0 0 180)
			(unlocked yes)
			(layer "B.Fab")
			(hide yes)
			(effects
				(font
					(size 1 1)
					(thickness 0.15)
				)
				(justify mirror)
			)
		)
		(property "Voltage" "50V"
			(at 0 0 180)
			(unlocked yes)
			(layer "B.Fab")
			(hide yes)
			(effects
				(font
					(size 1 1)
					(thickness 0.15)
				)
				(justify mirror)
			)
		)
		(property "Dielectric" "X5R"
			(at 0 0 180)
			(unlocked yes)
			(layer "B.Fab")
			(hide yes)
			(effects
				(font
					(size 1 1)
					(thickness 0.15)
				)
				(justify mirror)
			)
		)
		(property "Author" "Antmicro"
			(at 0 0 180)
			(unlocked yes)
			(layer "B.Fab")
			(hide yes)
			(effects
				(font
					(size 1 1)
					(thickness 0.15)
				)
				(justify mirror)
			)
		)
		(sheetname "/TB Controller - Power/")
		(sheetfile "tb-power.kicad_sch")
		(attr smd)
		(fp_rect
			(start -0.925 0.47)
			(end 0.925 -0.47)
			(stroke
				(width 0.05)
				(type default)
			)
			(fill no)
			(layer "B.CrtYd")
		)
		(fp_line
			(start 0.504 0.25)
			(end 0.504 -0.248)
			(stroke
				(width 0.15)
				(type solid)
			)
			(layer "B.Fab")
		)
		(fp_line
			(start 0.504 -0.248)
			(end -0.494 -0.248)
			(stroke
				(width 0.15)
				(type solid)
			)
			(layer "B.Fab")
		)
		(fp_line
			(start -0.494 0.25)
			(end 0.504 0.25)
			(stroke
				(width 0.15)
				(type solid)
			)
			(layer "B.Fab")
		)
		(fp_line
			(start -0.494 -0.248)
			(end -0.494 0.25)
			(stroke
				(width 0.15)
				(type solid)
			)
			(layer "B.Fab")
		)
		(fp_text user "License: Apache-2.0"
			(at -0.939 -5.799 0)
			(layer "B.Fab")
			(effects
				(font
					(size 0.7 0.7)
					(thickness 0.15)
				)
				(justify left bottom mirror)
			)
		)
		(fp_text user "${REFERENCE}"
			(at -0.939 -4.599 0)
			(layer "B.Fab")
			(effects
				(font
					(size 0.7 0.7)
					(thickness 0.15)
				)
				(justify left bottom mirror)
			)
		)
		(fp_text user "Author: Antmicro"
			(at -0.939 -3.399 0)
			(layer "B.Fab")
			(effects
				(font
					(size 0.7 0.7)
					(thickness 0.15)
				)
				(justify left bottom mirror)
			)
		)
		(pad "1" smd roundrect
			(at -0.48 0 180)
			(size 0.59 0.64)
			(layers "B.Cu" "B.Mask" "B.Paste")
			(roundrect_rratio 0.25)
			(net 23 "GND")
			(pintype "passive")
		)
		(pad "2" smd roundrect
			(at 0.48 0 180)
			(size 0.59 0.64)
			(layers "B.Cu" "B.Mask" "B.Paste")
			(roundrect_rratio 0.25)
			(net 57 "+3V3_TB")
			(pintype "passive")
		)
	)
	(footprint "antmicro-footprints:C_0402_1005Metric"
		(layer "B.Cu")
		(at 124.599998 123.950002 -90)
		(descr "Capacitor SMD 0402")
		(tags "capacitor SMD 0402")
		(property "Reference" "C65"
			(at -7.700002 -21.900002 90)
			(layer "B.SilkS")
			(effects
				(font
					(size 0.7 0.7)
					(thickness 0.15)
				)
				(justify mirror)
			)
		)
		(property "Value" "C_1u_0402"
			(at -1.022927 -2.155213 90)
			(layer "B.Fab")
			(effects
				(font
					(size 0.7 0.7)
					(thickness 0.15)
				)
				(justify left bottom mirror)
			)
		)
		(property "Datasheet" "https://product.tdk.com/en/search/capacitor/ceramic/mlcc/info?part_no=C1005X6S1A105K050BC"
			(at 0 0 90)
			(layer "B.Fab")
			(hide yes)
			(effects
				(font
					(size 1.27 1.27)
					(thickness 0.15)
				)
				(justify mirror)
			)
		)
		(property "Description" "SMD Multilayer Ceramic Capacitor, 1 µF, 10 V, 0402 [1005 Metric], ± 10%, X6S, C"
			(at 0 0 90)
			(layer "B.Fab")
			(hide yes)
			(effects
				(font
					(size 1.27 1.27)
					(thickness 0.15)
				)
				(justify mirror)
			)
		)
		(property "MPN" "C1005X6S1A105K050BC"
			(at 0 0 270)
			(unlocked yes)
			(layer "B.Fab")
			(hide yes)
			(effects
				(font
					(size 1 1)
					(thickness 0.15)
				)
				(justify mirror)
			)
		)
		(property "Manufacturer" "TDK"
			(at 0 0 270)
			(unlocked yes)
			(layer "B.Fab")
			(hide yes)
			(effects
				(font
					(size 1 1)
					(thickness 0.15)
				)
				(justify mirror)
			)
		)
		(property "License" "Apache-2.0"
			(at 0 0 270)
			(unlocked yes)
			(layer "B.Fab")
			(hide yes)
			(effects
				(font
					(size 1 1)
					(thickness 0.15)
				)
				(justify mirror)
			)
		)
		(property "Val" "1u"
			(at 0 0 270)
			(unlocked yes)
			(layer "B.Fab")
			(hide yes)
			(effects
				(font
					(size 1 1)
					(thickness 0.15)
				)
				(justify mirror)
			)
		)
		(property "Voltage" ""
			(at 0 0 270)
			(unlocked yes)
			(layer "B.Fab")
			(hide yes)
			(effects
				(font
					(size 1 1)
					(thickness 0.15)
				)
				(justify mirror)
			)
		)
		(property "Dielectric" ""
			(at 0 0 270)
			(unlocked yes)
			(layer "B.Fab")
			(hide yes)
			(effects
				(font
					(size 1 1)
					(thickness 0.15)
				)
				(justify mirror)
			)
		)
		(property "Author" "Antmicro"
			(at 0 0 270)
			(unlocked yes)
			(layer "B.Fab")
			(hide yes)
			(effects
				(font
					(size 1 1)
					(thickness 0.15)
				)
				(justify mirror)
			)
		)
		(sheetname "/TB Controller - Power/")
		(sheetfile "tb-power.kicad_sch")
		(attr smd)
		(fp_rect
			(start -0.925 0.47)
			(end 0.925 -0.47)
			(stroke
				(width 0.05)
				(type default)
			)
			(fill no)
			(layer "B.CrtYd")
		)
		(fp_line
			(start -0.494 0.25)
			(end 0.504 0.25)
			(stroke
				(width 0.15)
				(type solid)
			)
			(layer "B.Fab")
		)
		(fp_line
			(start 0.504 0.25)
			(end 0.504 -0.248)
			(stroke
				(width 0.15)
				(type solid)
			)
			(layer "B.Fab")
		)
		(fp_line
			(start -0.494 -0.248)
			(end -0.494 0.25)
			(stroke
				(width 0.15)
				(type solid)
			)
			(layer "B.Fab")
		)
		(fp_line
			(start 0.504 -0.248)
			(end -0.494 -0.248)
			(stroke
				(width 0.15)
				(type solid)
			)
			(layer "B.Fab")
		)
		(fp_text user "${REFERENCE}"
			(at -0.939 -4.599 90)
			(layer "B.Fab")
			(effects
				(font
					(size 0.7 0.7)
					(thickness 0.15)
				)
				(justify left bottom mirror)
			)
		)
		(fp_text user "Author: Antmicro"
			(at -0.939 -3.399 90)
			(layer "B.Fab")
			(effects
				(font
					(size 0.7 0.7)
					(thickness 0.15)
				)
				(justify left bottom mirror)
			)
		)
		(fp_text user "License: Apache-2.0"
			(at -0.939 -5.799 90)
			(layer "B.Fab")
			(effects
				(font
					(size 0.7 0.7)
					(thickness 0.15)
				)
				(justify left bottom mirror)
			)
		)
		(pad "1" smd roundrect
			(at -0.48 0 270)
			(size 0.59 0.64)
			(layers "B.Cu" "B.Mask" "B.Paste")
			(roundrect_rratio 0.25)
			(net 23 "GND")
			(pintype "passive")
		)
		(pad "2" smd roundrect
			(at 0.48 0 270)
			(size 0.59 0.64)
			(layers "B.Cu" "B.Mask" "B.Paste")
			(roundrect_rratio 0.25)
			(net 403 "Net-(C55-Pad2)")
			(pintype "passive")
		)
	)
	(footprint "antmicro-footprints:C_0402_1005Metric"
		(layer "B.Cu")
		(at 130.45 125.900001 -90)
		(descr "Capacitor SMD 0402")
		(tags "capacitor SMD 0402")
		(property "Reference" "C78"
			(at -7.700002 -21.900002 90)
			(layer "B.SilkS")
			(effects
				(font
					(size 0.7 0.7)
					(thickness 0.15)
				)
				(justify mirror)
			)
		)
		(property "Value" "C_1u_0402"
			(at -1.022927 -2.155213 90)
			(layer "B.Fab")
			(effects
				(font
					(size 0.7 0.7)
					(thickness 0.15)
				)
				(justify left bottom mirror)
			)
		)
		(property "Datasheet" "https://product.tdk.com/en/search/capacitor/ceramic/mlcc/info?part_no=C1005X6S1A105K050BC"
			(at 0 0 90)
			(layer "B.Fab")
			(hide yes)
			(effects
				(font
					(size 1.27 1.27)
					(thickness 0.15)
				)
				(justify mirror)
			)
		)
		(property "Description" "SMD Multilayer Ceramic Capacitor, 1 µF, 10 V, 0402 [1005 Metric], ± 10%, X6S, C"
			(at 0 0 90)
			(layer "B.Fab")
			(hide yes)
			(effects
				(font
					(size 1.27 1.27)
					(thickness 0.15)
				)
				(justify mirror)
			)
		)
		(property "MPN" "C1005X6S1A105K050BC"
			(at 0 0 270)
			(unlocked yes)
			(layer "B.Fab")
			(hide yes)
			(effects
				(font
					(size 1 1)
					(thickness 0.15)
				)
				(justify mirror)
			)
		)
		(property "Manufacturer" "TDK"
			(at 0 0 270)
			(unlocked yes)
			(layer "B.Fab")
			(hide yes)
			(effects
				(font
					(size 1 1)
					(thickness 0.15)
				)
				(justify mirror)
			)
		)
		(property "License" "Apache-2.0"
			(at 0 0 270)
			(unlocked yes)
			(layer "B.Fab")
			(hide yes)
			(effects
				(font
					(size 1 1)
					(thickness 0.15)
				)
				(justify mirror)
			)
		)
		(property "Val" "1u"
			(at 0 0 270)
			(unlocked yes)
			(layer "B.Fab")
			(hide yes)
			(effects
				(font
					(size 1 1)
					(thickness 0.15)
				)
				(justify mirror)
			)
		)
		(property "Voltage" ""
			(at 0 0 270)
			(unlocked yes)
			(layer "B.Fab")
			(hide yes)
			(effects
				(font
					(size 1 1)
					(thickness 0.15)
				)
				(justify mirror)
			)
		)
		(property "Dielectric" ""
			(at 0 0 270)
			(unlocked yes)
			(layer "B.Fab")
			(hide yes)
			(effects
				(font
					(size 1 1)
					(thickness 0.15)
				)
				(justify mirror)
			)
		)
		(property "Author" "Antmicro"
			(at 0 0 270)
			(unlocked yes)
			(layer "B.Fab")
			(hide yes)
			(effects
				(font
					(size 1 1)
					(thickness 0.15)
				)
				(justify mirror)
			)
		)
		(sheetname "/TB Controller - Power/")
		(sheetfile "tb-power.kicad_sch")
		(attr smd)
		(fp_rect
			(start -0.925 0.47)
			(end 0.925 -0.47)
			(stroke
				(width 0.05)
				(type default)
			)
			(fill no)
			(layer "B.CrtYd")
		)
		(fp_line
			(start -0.494 0.25)
			(end 0.504 0.25)
			(stroke
				(width 0.15)
				(type solid)
			)
			(layer "B.Fab")
		)
		(fp_line
			(start 0.504 0.25)
			(end 0.504 -0.248)
			(stroke
				(width 0.15)
				(type solid)
			)
			(layer "B.Fab")
		)
		(fp_line
			(start -0.494 -0.248)
			(end -0.494 0.25)
			(stroke
				(width 0.15)
				(type solid)
			)
			(layer "B.Fab")
		)
		(fp_line
			(start 0.504 -0.248)
			(end -0.494 -0.248)
			(stroke
				(width 0.15)
				(type solid)
			)
			(layer "B.Fab")
		)
		(fp_text user "License: Apache-2.0"
			(at -0.939 -5.799 90)
			(layer "B.Fab")
			(effects
				(font
					(size 0.7 0.7)
					(thickness 0.15)
				)
				(justify left bottom mirror)
			)
		)
		(fp_text user "${REFERENCE}"
			(at -0.939 -4.599 90)
			(layer "B.Fab")
			(effects
				(font
					(size 0.7 0.7)
					(thickness 0.15)
				)
				(justify left bottom mirror)
			)
		)
		(fp_text user "Author: Antmicro"
			(at -0.939 -3.399 90)
			(layer "B.Fab")
			(effects
				(font
					(size 0.7 0.7)
					(thickness 0.15)
				)
				(justify left bottom mirror)
			)
		)
		(pad "1" smd roundrect
			(at -0.48 0 270)
			(size 0.59 0.64)
			(layers "B.Cu" "B.Mask" "B.Paste")
			(roundrect_rratio 0.25)
			(net 23 "GND")
			(pintype "passive")
		)
		(pad "2" smd roundrect
			(at 0.48 0 270)
			(size 0.59 0.64)
			(layers "B.Cu" "B.Mask" "B.Paste")
			(roundrect_rratio 0.25)
			(net 57 "+3V3_TB")
			(pintype "passive")
		)
	)
)
